(kicad_pcb
	(version 20260206)
	(generator "pcbnew")
	(generator_version "10.0")
	(general
		(thickness 1.6)
		(legacy_teardrops no)
	)
	(paper "A4")
	(title_block
		(title "Bryce Canyon_F.DPB_16315-1-OCP.brd")
		(comment 1 "Bryce Canyon / footprints 1176-1183 of 2223")
	)
	(layers
		(0 "F.Cu" signal "TOP")
		(4 "In1.Cu" signal "L2GND")
		(6 "In2.Cu" signal "L3")
		(8 "In3.Cu" signal "L4GND")
		(10 "In4.Cu" signal "L5")
		(12 "In5.Cu" signal "L6VCC")
		(14 "In6.Cu" signal "L7VCC")
		(16 "In7.Cu" signal "L8")
		(18 "In8.Cu" signal "L9GND")
		(20 "In9.Cu" signal "L10")
		(22 "In10.Cu" signal "L11GND")
		(2 "B.Cu" signal "BOTTOM")
		(9 "F.Adhes" user "F.Adhesive")
		(11 "B.Adhes" user "B.Adhesive")
		(13 "F.Paste" user "Package Geometry/Pastemask Top")
		(15 "B.Paste" user "Package Geometry/Pastemask Bottom")
		(5 "F.SilkS" user "Ref Des/Silkscreen Top")
		(7 "B.SilkS" user "Ref Des/Silkscreen Bottom")
		(1 "F.Mask" user "Board Geometry/Soldermask Top")
		(3 "B.Mask" user "Board Geometry/Soldermask Bottom")
		(17 "Dwgs.User" user "User.Drawings")
		(19 "Cmts.User" user "User.Comments")
		(21 "Eco1.User" user "User.Eco1")
		(23 "Eco2.User" user "User.Eco2")
		(25 "Edge.Cuts" user "Board Geometry/Outline")
		(27 "Margin" user)
		(31 "F.CrtYd" user "Package Geometry/Place Bound Top")
		(29 "B.CrtYd" user "Package Geometry/Place Bound Bottom")
		(35 "F.Fab" user "Ref Des/Assembly Top")
		(33 "B.Fab" user "Ref Des/Assembly Bottom")
	)
	(footprint ""
		(layer "F.Cu")
		(at 315.149992 -209.399886)
		(property "Reference" "FLED7"
			(at 0 0 0)
			(layer "F.SilkS")
			(hide yes)
			(effects
				(font
					(size 1.27 1.27)
				)
			)
		)
		(property "Value" "LED-BY-19-GP"
			(at -2.132076 1.414018 0)
			(unlocked yes)
			(layer "F.Fab")
			(hide yes)
			(effects
				(font
					(size 1.016 1.016)
					(thickness 0.1524)
				)
			)
		)
		(property "Device Type" "LED-1615-4PH26"
			(at -2.132076 -0.109982 0)
			(unlocked yes)
			(layer "F.Fab")
			(hide yes)
			(effects
				(font
					(size 1.016 1.016)
					(thickness 0.1524)
				)
			)
		)
		(duplicate_pad_numbers_are_jumpers no)
		(fp_line
			(start -1.2954 0.254)
			(end -1.2954 1.6002)
			(stroke
				(width 0.508)
				(type default)
			)
			(layer "F.SilkS")
		)
		(fp_line
			(start -1.2954 1.6002)
			(end 1.2954 1.6002)
			(stroke
				(width 0.508)
				(type default)
			)
			(layer "F.SilkS")
		)
		(fp_line
			(start -1.1176 -1.4224)
			(end 1.1176 -1.4224)
			(stroke
				(width 0.1524)
				(type default)
			)
			(layer "F.SilkS")
		)
		(fp_line
			(start -1.1176 1.4224)
			(end -1.1176 -1.4224)
			(stroke
				(width 0.1524)
				(type default)
			)
			(layer "F.SilkS")
		)
		(fp_line
			(start 1.1176 -1.4224)
			(end 1.1176 1.4224)
			(stroke
				(width 0.1524)
				(type default)
			)
			(layer "F.SilkS")
		)
		(fp_line
			(start 1.1176 1.4224)
			(end -1.1176 1.4224)
			(stroke
				(width 0.1524)
				(type default)
			)
			(layer "F.SilkS")
		)
		(fp_line
			(start 1.2954 1.6002)
			(end 1.2954 0.254)
			(stroke
				(width 0.508)
				(type default)
			)
			(layer "F.SilkS")
		)
		(fp_rect
			(start -0.7493 0.8001)
			(end 0.7493 -0.8001)
			(stroke
				(width 0)
				(type default)
			)
			(fill no)
			(layer "F.CrtYd")
		)
		(fp_poly
			(pts
				(xy -1.3716 1.6764) (xy -1.3716 -1.6764) (xy 1.3716 -1.6764) (xy 1.3716 0.0635) (xy 0.7493 0.0635)
				(xy 0.7493 -0.8001) (xy -0.7493 -0.8001) (xy -0.7493 0.8001) (xy 0.7493 0.8001) (xy 0.7493 0.0762)
				(xy 1.3716 0.0762) (xy 1.3716 1.6764)
			)
			(stroke
				(width 0)
				(type default)
			)
			(fill no)
			(layer "F.CrtYd")
		)
		(fp_rect
			(start -1.3716 1.6764)
			(end 1.3716 -1.6764)
			(stroke
				(width 0)
				(type default)
			)
			(fill no)
			(layer "F.Fab")
		)
		(pad "1" smd rect
			(at 0.50038 -0.73025)
			(size 0.7112 0.8636)
			(layers "F.Cu" "F.Mask" "F.Paste")
			(net "DRV_ACT_6")
		)
		(pad "2" smd rect
			(at -0.50038 -0.73025)
			(size 0.7112 0.8636)
			(layers "F.Cu" "F.Mask" "F.Paste")
			(net "FLT_HDD6")
		)
		(pad "3" smd rect
			(at 0.50038 0.73025)
			(size 0.7112 0.8636)
			(layers "F.Cu" "F.Mask" "F.Paste")
			(net "DRV_ACT_6_N")
		)
		(pad "4" smd rect
			(at -0.50038 0.73025)
			(size 0.7112 0.8636)
			(layers "F.Cu" "F.Mask" "F.Paste")
			(net "FLT_HDD6_N")
		)
	)
	(footprint ""
		(layer "F.Cu")
		(at 79.974948 -161.649918 180)
		(property "Reference" "D14"
			(at 0 0 180)
			(layer "F.SilkS")
			(hide yes)
			(effects
				(font
					(size 1.27 1.27)
				)
			)
		)
		(property "Value" "RB551V30-GP"
			(at 0 -6.7818 180)
			(unlocked yes)
			(layer "F.Fab")
			(hide yes)
			(effects
				(font
					(size 1.016 1.016)
					(thickness 0.1524)
				)
			)
		)
		(property "Device Type" "SOD323AKH38"
			(at 0 -8.6868 180)
			(unlocked yes)
			(layer "F.Fab")
			(hide yes)
			(effects
				(font
					(size 1.016 1.016)
					(thickness 0.1524)
				)
			)
		)
		(duplicate_pad_numbers_are_jumpers no)
		(fp_line
			(start 0.889 2.159)
			(end -0.889 2.159)
			(stroke
				(width 0.1524)
				(type default)
			)
			(layer "F.SilkS")
		)
		(fp_line
			(start 0.889 -1.9304)
			(end 0.889 2.159)
			(stroke
				(width 0.1524)
				(type default)
			)
			(layer "F.SilkS")
		)
		(fp_line
			(start 0.762 2.0574)
			(end -0.762 2.0574)
			(stroke
				(width 0.508)
				(type default)
			)
			(layer "F.SilkS")
		)
		(fp_line
			(start -0.889 2.159)
			(end -0.889 -1.9304)
			(stroke
				(width 0.1524)
				(type default)
			)
			(layer "F.SilkS")
		)
		(fp_line
			(start -0.889 -1.9304)
			(end 0.889 -1.9304)
			(stroke
				(width 0.1524)
				(type default)
			)
			(layer "F.SilkS")
		)
		(fp_rect
			(start -1.016 2.3114)
			(end 1.016 -2.0066)
			(stroke
				(width 0)
				(type default)
			)
			(fill no)
			(layer "F.CrtYd")
		)
		(fp_poly
			(pts
				(xy -1.016 -2.0066) (xy 1.016 -2.0066) (xy 1.016 2.3114) (xy -1.016 2.3114)
			)
			(stroke
				(width 0)
				(type default)
			)
			(fill no)
			(layer "F.Fab")
		)
		(pad "A" smd rect
			(at 0 -1.143 180)
			(size 0.5588 1.016)
			(layers "F.Cu" "F.Mask" "F.Paste")
			(net "SW_HDD_R14")
		)
		(pad "K" smd rect
			(at 0 1.143 180)
			(size 0.5588 1.016)
			(layers "F.Cu" "F.Mask" "F.Paste")
			(net "SW_HDD_N14")
		)
	)
	(footprint ""
		(layer "F.Cu")
		(at 239.014 -395.9098 180)
		(property "Reference" "R1165"
			(at 0 0 180)
			(layer "F.SilkS")
			(hide yes)
			(effects
				(font
					(size 1.27 1.27)
				)
			)
		)
		(property "Value" "12K4R2F-GP"
			(at 0.064008 -3.993896 180)
			(unlocked yes)
			(layer "F.Fab")
			(hide yes)
			(effects
				(font
					(size 1.016 1.016)
					(thickness 0.1524)
				)
			)
		)
		(property "Device Type" "R402H16"
			(at 0.064008 -5.517896 180)
			(unlocked yes)
			(layer "F.Fab")
			(hide yes)
			(effects
				(font
					(size 1.016 1.016)
					(thickness 0.1524)
				)
			)
		)
		(duplicate_pad_numbers_are_jumpers no)
		(fp_line
			(start 0.508 -0.9398)
			(end -0.508 -0.9398)
			(stroke
				(width 0.1524)
				(type default)
			)
			(layer "F.SilkS")
		)
		(fp_line
			(start -0.508 -0.9398)
			(end -0.508 0.9398)
			(stroke
				(width 0.1524)
				(type default)
			)
			(layer "F.SilkS")
		)
		(fp_rect
			(start -0.508 0.9398)
			(end 0.508 -0.9398)
			(stroke
				(width 0)
				(type default)
			)
			(fill no)
			(layer "F.CrtYd")
		)
		(fp_rect
			(start -0.508 0.9398)
			(end 0.508 -0.9398)
			(stroke
				(width 0)
				(type default)
			)
			(fill no)
			(layer "F.Fab")
		)
		(pad "1" smd custom
			(at 0 -0.4445 180)
			(size 0.1397 0.1397)
			(layers "F.Cu" "F.Mask" "F.Paste")
			(net "MB3_ISTART_R")
			(options
				(clearance outline)
				(anchor circle)
			)
			(primitives
				(gr_poly
					(pts
						(arc
							(start -0.1778 -0.2794)
							(mid -0.249642 -0.249642)
							(end -0.2794 -0.1778)
						)
						(arc
							(start -0.2794 0.1778)
							(mid -0.249642 0.249642)
							(end -0.1778 0.2794)
						)
						(arc
							(start 0.1778 0.2794)
							(mid 0.249642 0.249642)
							(end 0.2794 0.1778)
						)
						(arc
							(start 0.2794 -0.1778)
							(mid 0.249642 -0.249642)
							(end 0.1778 -0.2794)
						)
					)
					(width 0)
					(fill yes)
				)
			)
		)
		(pad "2" smd custom
			(at 0 0.4445 180)
			(size 0.1397 0.1397)
			(layers "F.Cu" "F.Mask" "F.Paste")
			(net "AGND_CURRENT_DPB")
			(options
				(clearance outline)
				(anchor circle)
			)
			(primitives
				(gr_poly
					(pts
						(arc
							(start -0.1778 -0.2794)
							(mid -0.249642 -0.249642)
							(end -0.2794 -0.1778)
						)
						(arc
							(start -0.2794 0.1778)
							(mid -0.249642 0.249642)
							(end -0.1778 0.2794)
						)
						(arc
							(start 0.1778 0.2794)
							(mid 0.249642 0.249642)
							(end 0.2794 0.1778)
						)
						(arc
							(start 0.2794 -0.1778)
							(mid 0.249642 -0.249642)
							(end 0.1778 -0.2794)
						)
					)
					(width 0)
					(fill yes)
				)
			)
		)
	)
	(footprint ""
		(layer "F.Cu")
		(at 479.036126 -301.287942)
		(property "Reference" "C187"
			(at 0 0 0)
			(layer "F.SilkS")
			(hide yes)
			(effects
				(font
					(size 1.27 1.27)
				)
			)
		)
		(property "Value" "SC4D7U25V5KX-1-GP"
			(at -0.0762 -6.1214 0)
			(unlocked yes)
			(layer "F.Fab")
			(hide yes)
			(effects
				(font
					(size 1.016 1.016)
					(thickness 0.1524)
				)
			)
		)
		(property "Device Type" "C805H58"
			(at -0.0762 -8.1534 0)
			(unlocked yes)
			(layer "F.Fab")
			(hide yes)
			(effects
				(font
					(size 1.016 1.016)
					(thickness 0.1524)
				)
			)
		)
		(duplicate_pad_numbers_are_jumpers no)
		(fp_line
			(start 0.635 0)
			(end -0.635 0)
			(stroke
				(width 0.508)
				(type default)
			)
			(layer "F.SilkS")
		)
		(fp_rect
			(start -0.9652 1.778)
			(end 0.9652 -1.778)
			(stroke
				(width 0)
				(type default)
			)
			(fill no)
			(layer "F.CrtYd")
		)
		(fp_poly
			(pts
				(xy -0.9652 -1.778) (xy 0.9652 -1.778) (xy 0.9652 1.778) (xy -0.9652 1.778)
			)
			(stroke
				(width 0)
				(type default)
			)
			(fill no)
			(layer "F.Fab")
		)
		(pad "1" smd rect
			(at 0 -0.9652)
			(size 1.397 1.143)
			(layers "F.Cu" "F.Mask" "F.Paste")
			(net "P12V_HDD11")
		)
		(pad "2" smd rect
			(at 0 0.9652)
			(size 1.397 1.143)
			(layers "F.Cu" "F.Mask" "F.Paste")
			(net "GND")
		)
	)
	(footprint ""
		(layer "F.Cu")
		(at 337.312 -162.792918 90)
		(property "Reference" "D18"
			(at 0 0 90)
			(layer "F.SilkS")
			(hide yes)
			(effects
				(font
					(size 1.27 1.27)
				)
			)
		)
		(property "Value" "RB551V30-GP"
			(at 0 -6.7818 90)
			(unlocked yes)
			(layer "F.Fab")
			(hide yes)
			(effects
				(font
					(size 1.016 1.016)
					(thickness 0.1524)
				)
			)
		)
		(property "Device Type" "SOD323AKH38"
			(at 0 -8.6868 90)
			(unlocked yes)
			(layer "F.Fab")
			(hide yes)
			(effects
				(font
					(size 1.016 1.016)
					(thickness 0.1524)
				)
			)
		)
		(duplicate_pad_numbers_are_jumpers no)
		(fp_line
			(start 0.889 -1.9304)
			(end 0.889 2.159)
			(stroke
				(width 0.1524)
				(type default)
			)
			(layer "F.SilkS")
		)
		(fp_line
			(start -0.889 -1.9304)
			(end 0.889 -1.9304)
			(stroke
				(width 0.1524)
				(type default)
			)
			(layer "F.SilkS")
		)
		(fp_line
			(start 0.762 2.0574)
			(end -0.762 2.0574)
			(stroke
				(width 0.508)
				(type default)
			)
			(layer "F.SilkS")
		)
		(fp_line
			(start 0.889 2.159)
			(end -0.889 2.159)
			(stroke
				(width 0.1524)
				(type default)
			)
			(layer "F.SilkS")
		)
		(fp_line
			(start -0.889 2.159)
			(end -0.889 -1.9304)
			(stroke
				(width 0.1524)
				(type default)
			)
			(layer "F.SilkS")
		)
		(fp_rect
			(start -1.016 2.3114)
			(end 1.016 -2.0066)
			(stroke
				(width 0)
				(type default)
			)
			(fill no)
			(layer "F.CrtYd")
		)
		(fp_poly
			(pts
				(xy -1.016 -2.0066) (xy 1.016 -2.0066) (xy 1.016 2.3114) (xy -1.016 2.3114)
			)
			(stroke
				(width 0)
				(type default)
			)
			(fill no)
			(layer "F.Fab")
		)
		(pad "A" smd rect
			(at 0 -1.143 90)
			(size 0.5588 1.016)
			(layers "F.Cu" "F.Mask" "F.Paste")
			(net "SW_HDD_R18")
		)
		(pad "K" smd rect
			(at 0 1.143 90)
			(size 0.5588 1.016)
			(layers "F.Cu" "F.Mask" "F.Paste")
			(net "SW_HDD_N18")
		)
	)
	(footprint ""
		(layer "F.Cu")
		(at 146.630898 -62.778894 -90)
		(property "Reference" "C404"
			(at 0 0 270)
			(layer "F.SilkS")
			(hide yes)
			(effects
				(font
					(size 1.27 1.27)
				)
			)
		)
		(property "Value" "SC1U16V3KX-5GP"
			(at 0 -2.8194 270)
			(unlocked yes)
			(layer "F.Fab")
			(hide yes)
			(effects
				(font
					(size 1.016 1.016)
					(thickness 0.1524)
				)
			)
		)
		(property "Device Type" "C603H36"
			(at 0 -4.3434 270)
			(unlocked yes)
			(layer "F.Fab")
			(hide yes)
			(effects
				(font
					(size 1.016 1.016)
					(thickness 0.1524)
				)
			)
		)
		(duplicate_pad_numbers_are_jumpers no)
		(fp_line
			(start 0.508 0)
			(end -0.508 0)
			(stroke
				(width 0.2032)
				(type default)
			)
			(layer "F.SilkS")
		)
		(fp_rect
			(start -0.5842 1.3335)
			(end 0.5842 -1.3335)
			(stroke
				(width 0)
				(type default)
			)
			(fill no)
			(layer "F.CrtYd")
		)
		(fp_rect
			(start -0.5842 1.3335)
			(end 0.5842 -1.3335)
			(stroke
				(width 0)
				(type default)
			)
			(fill no)
			(layer "F.Fab")
		)
		(pad "1" smd custom
			(at 0 -0.762 270)
			(size 0.2159 0.2159)
			(layers "F.Cu" "F.Mask" "F.Paste")
			(net "P5V_HDD28")
			(options
				(clearance outline)
				(anchor circle)
			)
			(primitives
				(gr_poly
					(pts
						(arc
							(start -0.3302 -0.4318)
							(mid -0.402042 -0.402042)
							(end -0.4318 -0.3302)
						)
						(arc
							(start -0.4318 0.3302)
							(mid -0.402042 0.402042)
							(end -0.3302 0.4318)
						)
						(arc
							(start 0.3302 0.4318)
							(mid 0.402042 0.402042)
							(end 0.4318 0.3302)
						)
						(arc
							(start 0.4318 -0.3302)
							(mid 0.402042 -0.402042)
							(end 0.3302 -0.4318)
						)
					)
					(width 0)
					(fill yes)
				)
			)
		)
		(pad "2" smd custom
			(at 0 0.762 270)
			(size 0.2159 0.2159)
			(layers "F.Cu" "F.Mask" "F.Paste")
			(net "GND")
			(options
				(clearance outline)
				(anchor circle)
			)
			(primitives
				(gr_poly
					(pts
						(arc
							(start -0.3302 -0.4318)
							(mid -0.402042 -0.402042)
							(end -0.4318 -0.3302)
						)
						(arc
							(start -0.4318 0.3302)
							(mid -0.402042 0.402042)
							(end -0.3302 0.4318)
						)
						(arc
							(start 0.3302 0.4318)
							(mid 0.402042 0.402042)
							(end 0.4318 0.3302)
						)
						(arc
							(start 0.4318 -0.3302)
							(mid 0.402042 -0.402042)
							(end 0.3302 -0.4318)
						)
					)
					(width 0)
					(fill yes)
				)
			)
		)
	)
	(footprint ""
		(layer "F.Cu")
		(at 283.21 -284.5308 180)
		(property "Reference" "R125"
			(at 0 0 180)
			(layer "F.SilkS")
			(hide yes)
			(effects
				(font
					(size 1.27 1.27)
				)
			)
		)
		(property "Value" "0R2J-2-GP"
			(at 0.064008 -3.993896 180)
			(unlocked yes)
			(layer "F.Fab")
			(hide yes)
			(effects
				(font
					(size 1.016 1.016)
					(thickness 0.1524)
				)
			)
		)
		(property "Device Type" "R402H16"
			(at 0.064008 -5.517896 180)
			(unlocked yes)
			(layer "F.Fab")
			(hide yes)
			(effects
				(font
					(size 1.016 1.016)
					(thickness 0.1524)
				)
			)
		)
		(duplicate_pad_numbers_are_jumpers no)
		(fp_line
			(start 0.508 -0.9398)
			(end -0.508 -0.9398)
			(stroke
				(width 0.1524)
				(type default)
			)
			(layer "F.SilkS")
		)
		(fp_line
			(start -0.508 -0.9398)
			(end -0.508 0.9398)
			(stroke
				(width 0.1524)
				(type default)
			)
			(layer "F.SilkS")
		)
		(fp_rect
			(start -0.508 0.9398)
			(end 0.508 -0.9398)
			(stroke
				(width 0)
				(type default)
			)
			(fill no)
			(layer "F.CrtYd")
		)
		(fp_rect
			(start -0.508 0.9398)
			(end 0.508 -0.9398)
			(stroke
				(width 0)
				(type default)
			)
			(fill no)
			(layer "F.Fab")
		)
		(pad "1" smd custom
			(at 0 -0.4445 180)
			(size 0.1397 0.1397)
			(layers "F.Cu" "F.Mask" "F.Paste")
			(net "IO_EXP2_LED_SDA")
			(options
				(clearance outline)
				(anchor circle)
			)
			(primitives
				(gr_poly
					(pts
						(arc
							(start -0.1778 -0.2794)
							(mid -0.249642 -0.249642)
							(end -0.2794 -0.1778)
						)
						(arc
							(start -0.2794 0.1778)
							(mid -0.249642 0.249642)
							(end -0.1778 0.2794)
						)
						(arc
							(start 0.1778 0.2794)
							(mid 0.249642 0.249642)
							(end 0.2794 0.1778)
						)
						(arc
							(start 0.2794 -0.1778)
							(mid 0.249642 -0.249642)
							(end 0.1778 -0.2794)
						)
					)
					(width 0)
					(fill yes)
				)
			)
		)
		(pad "2" smd custom
			(at 0 0.4445 180)
			(size 0.1397 0.1397)
			(layers "F.Cu" "F.Mask" "F.Paste")
			(net "I2C_DRIVE_A_FLT_LED_SDA")
			(options
				(clearance outline)
				(anchor circle)
			)
			(primitives
				(gr_poly
					(pts
						(arc
							(start -0.1778 -0.2794)
							(mid -0.249642 -0.249642)
							(end -0.2794 -0.1778)
						)
						(arc
							(start -0.2794 0.1778)
							(mid -0.249642 0.249642)
							(end -0.1778 0.2794)
						)
						(arc
							(start 0.1778 0.2794)
							(mid 0.249642 0.249642)
							(end 0.2794 0.1778)
						)
						(arc
							(start 0.2794 -0.1778)
							(mid 0.249642 -0.249642)
							(end 0.1778 -0.2794)
						)
					)
					(width 0)
					(fill yes)
				)
			)
		)
	)
	(footprint ""
		(layer "F.Cu")
		(at 118.585996 -71.287894)
		(property "Reference" "C397"
			(at 0 0 0)
			(layer "F.SilkS")
			(hide yes)
			(effects
				(font
					(size 1.27 1.27)
				)
			)
		)
		(property "Value" "SC4D7U25V5KX-1-GP"
			(at -0.0762 -6.1214 0)
			(unlocked yes)
			(layer "F.Fab")
			(hide yes)
			(effects
				(font
					(size 1.016 1.016)
					(thickness 0.1524)
				)
			)
		)
		(property "Device Type" "C805H58"
			(at -0.0762 -8.1534 0)
			(unlocked yes)
			(layer "F.Fab")
			(hide yes)
			(effects
				(font
					(size 1.016 1.016)
					(thickness 0.1524)
				)
			)
		)
		(duplicate_pad_numbers_are_jumpers no)
		(fp_line
			(start 0.635 0)
			(end -0.635 0)
			(stroke
				(width 0.508)
				(type default)
			)
			(layer "F.SilkS")
		)
		(fp_rect
			(start -0.9652 1.778)
			(end 0.9652 -1.778)
			(stroke
				(width 0)
				(type default)
			)
			(fill no)
			(layer "F.CrtYd")
		)
		(fp_poly
			(pts
				(xy -0.9652 -1.778) (xy 0.9652 -1.778) (xy 0.9652 1.778) (xy -0.9652 1.778)
			)
			(stroke
				(width 0)
				(type default)
			)
			(fill no)
			(layer "F.Fab")
		)
		(pad "1" smd rect
			(at 0 -0.9652)
			(size 1.397 1.143)
			(layers "F.Cu" "F.Mask" "F.Paste")
			(net "P12V_HDD27")
		)
		(pad "2" smd rect
			(at 0 0.9652)
			(size 1.397 1.143)
			(layers "F.Cu" "F.Mask" "F.Paste")
			(net "GND")
		)
	)
)
